(kicad_pcb
	(version 20260206)
	(generator "pcbnew")
	(generator_version "10.0")
	(general
		(thickness 1.6)
		(legacy_teardrops no)
	)
	(paper "A4")
	(title_block
		(title "01162023_DA0F0TEBIF0_F0T_Expander_BD_F_brd_V02_OCP.brd")
		(comment 1 "Grand Teton / footprints 8176-8183 of 9728")
	)
	(layers
		(0 "F.Cu" signal "TOP")
		(4 "In1.Cu" signal "GND")
		(6 "In2.Cu" signal "VCC")
		(8 "In3.Cu" signal "VCC1")
		(10 "In4.Cu" signal "GND1")
		(12 "In5.Cu" signal "IN1")
		(14 "In6.Cu" signal "GND2")
		(16 "In7.Cu" signal "IN2")
		(18 "In8.Cu" signal "GND3")
		(20 "In9.Cu" signal "IN3")
		(22 "In10.Cu" signal "GND4")
		(24 "In11.Cu" signal "IN4")
		(26 "In12.Cu" signal "GND5")
		(28 "In13.Cu" signal "IN5")
		(30 "In14.Cu" signal "GND6")
		(32 "In15.Cu" signal "IN6")
		(34 "In16.Cu" signal "GND7")
		(2 "B.Cu" signal "BOTTOM")
		(9 "F.Adhes" user "F.Adhesive")
		(11 "B.Adhes" user "B.Adhesive")
		(13 "F.Paste" user "Package Geometry/Pastemask Top")
		(15 "B.Paste" user "Package Geometry/Pastemask Bottom")
		(5 "F.SilkS" user "Ref Des/Silkscreen Top")
		(7 "B.SilkS" user "Ref Des/Silkscreen Bottom")
		(1 "F.Mask" user "Board Geometry/Soldermask Top")
		(3 "B.Mask" user "Board Geometry/Soldermask Bottom")
		(17 "Dwgs.User" user "User.Drawings")
		(19 "Cmts.User" user "User.Comments")
		(21 "Eco1.User" user "User.Eco1")
		(23 "Eco2.User" user "User.Eco2")
		(25 "Edge.Cuts" user "Board Geometry/Outline")
		(27 "Margin" user)
		(31 "F.CrtYd" user "Package Geometry/Place Bound Top")
		(29 "B.CrtYd" user "Package Geometry/Place Bound Bottom")
		(35 "F.Fab" user "Ref Des/Assembly Top")
		(33 "B.Fab" user "Ref Des/Assembly Bottom")
	)
	(footprint ""
		(layer "B.Cu")
		(at 396.0749 -294.132 -90)
		(property "Reference" "C3569"
			(at 0 0 90)
			(layer "B.SilkS")
			(hide yes)
			(effects
				(font
					(size 1.27 1.27)
				)
				(justify mirror)
			)
		)
		(property "Value" ""
			(at 0 0 90)
			(layer "B.Fab")
			(effects
				(font
					(size 1.27 1.27)
				)
				(justify mirror)
			)
		)
		(duplicate_pad_numbers_are_jumpers no)
		(fp_line
			(start -0.299974 0.150114)
			(end 0.299974 0.150114)
			(stroke
				(width 0.1)
				(type default)
			)
			(layer "B.Fab")
		)
		(fp_line
			(start 0.299974 0.150114)
			(end 0.299974 -0.150114)
			(stroke
				(width 0.1)
				(type default)
			)
			(layer "B.Fab")
		)
		(fp_line
			(start -0.299974 -0.150114)
			(end -0.299974 0.150114)
			(stroke
				(width 0.1)
				(type default)
			)
			(layer "B.Fab")
		)
		(fp_line
			(start 0.299974 -0.150114)
			(end -0.299974 -0.150114)
			(stroke
				(width 0.1)
				(type default)
			)
			(layer "B.Fab")
		)
		(pad "1" smd rect
			(at 0.2667 0 90)
			(size 0.3048 0.381)
			(layers "B.Cu" "B.Mask" "B.Paste")
			(net "PCEPLL5_VDDA18_PEX3")
		)
		(pad "2" smd rect
			(at -0.2667 0 90)
			(size 0.3048 0.381)
			(layers "B.Cu" "B.Mask" "B.Paste")
			(net "GND")
		)
	)
	(footprint ""
		(layer "B.Cu")
		(at 224.848674 -371.055138 180)
		(property "Reference" "PR31"
			(at 0 0 0)
			(layer "B.SilkS")
			(hide yes)
			(effects
				(font
					(size 1.27 1.27)
				)
				(justify mirror)
			)
		)
		(property "Value" ""
			(at 0 0 0)
			(layer "B.Fab")
			(effects
				(font
					(size 1.27 1.27)
				)
				(justify mirror)
			)
		)
		(duplicate_pad_numbers_are_jumpers no)
		(fp_line
			(start 0.7874 0.4064)
			(end 0.7874 -0.4064)
			(stroke
				(width 0.1524)
				(type default)
			)
			(layer "B.SilkS")
		)
		(fp_line
			(start 0.7874 -0.4064)
			(end -0.7874 -0.4064)
			(stroke
				(width 0.1524)
				(type default)
			)
			(layer "B.SilkS")
		)
		(fp_line
			(start -0.7874 0.4064)
			(end 0.7874 0.4064)
			(stroke
				(width 0.1524)
				(type default)
			)
			(layer "B.SilkS")
		)
		(fp_line
			(start -0.7874 -0.4064)
			(end -0.7874 0.4064)
			(stroke
				(width 0.1524)
				(type default)
			)
			(layer "B.SilkS")
		)
		(fp_line
			(start 0.67945 0.3048)
			(end 0.67945 -0.305054)
			(stroke
				(width 0.1)
				(type default)
			)
			(layer "B.Fab")
		)
		(fp_line
			(start 0.67945 -0.305054)
			(end 0.12065 -0.305054)
			(stroke
				(width 0.1)
				(type default)
			)
			(layer "B.Fab")
		)
		(fp_line
			(start 0.12065 0.3048)
			(end 0.67945 0.3048)
			(stroke
				(width 0.1)
				(type default)
			)
			(layer "B.Fab")
		)
		(fp_line
			(start 0.12065 0.2794)
			(end 0.12065 0.3048)
			(stroke
				(width 0.1)
				(type default)
			)
			(layer "B.Fab")
		)
		(fp_line
			(start 0.12065 -0.2794)
			(end -0.12065 -0.2794)
			(stroke
				(width 0.1)
				(type default)
			)
			(layer "B.Fab")
		)
		(fp_line
			(start 0.12065 -0.305054)
			(end 0.12065 -0.2794)
			(stroke
				(width 0.1)
				(type default)
			)
			(layer "B.Fab")
		)
		(fp_line
			(start -0.120396 0.3048)
			(end -0.120396 0.2794)
			(stroke
				(width 0.1)
				(type default)
			)
			(layer "B.Fab")
		)
		(fp_line
			(start -0.120396 0.2794)
			(end 0.12065 0.2794)
			(stroke
				(width 0.1)
				(type default)
			)
			(layer "B.Fab")
		)
		(fp_line
			(start -0.12065 -0.2794)
			(end -0.12065 -0.3048)
			(stroke
				(width 0.1)
				(type default)
			)
			(layer "B.Fab")
		)
		(fp_line
			(start -0.12065 -0.3048)
			(end -0.67945 -0.3048)
			(stroke
				(width 0.1)
				(type default)
			)
			(layer "B.Fab")
		)
		(fp_line
			(start -0.67945 0.3048)
			(end -0.120396 0.3048)
			(stroke
				(width 0.1)
				(type default)
			)
			(layer "B.Fab")
		)
		(fp_line
			(start -0.67945 -0.3048)
			(end -0.67945 0.3048)
			(stroke
				(width 0.1)
				(type default)
			)
			(layer "B.Fab")
		)
		(pad "1" smd circle
			(at 0.40005 0)
			(size 0 0)
			(layers "B.Cu" "B.Mask" "B.Paste")
			(net "HSC_FAULT_N_1")
		)
		(pad "2" smd circle
			(at -0.40005 0)
			(size 0 0)
			(layers "B.Cu" "B.Mask" "B.Paste")
			(net "HSC_FAULT_N")
		)
	)
	(footprint ""
		(layer "B.Cu")
		(at 244.782086 -284.252162 180)
		(property "Reference" "PC253"
			(at 0 0 0)
			(layer "B.SilkS")
			(hide yes)
			(effects
				(font
					(size 1.27 1.27)
				)
				(justify mirror)
			)
		)
		(property "Value" ""
			(at 0 0 0)
			(layer "B.Fab")
			(effects
				(font
					(size 1.27 1.27)
				)
				(justify mirror)
			)
		)
		(duplicate_pad_numbers_are_jumpers no)
		(fp_line
			(start 1.524 0.762)
			(end 1.524 -0.762)
			(stroke
				(width 0.1524)
				(type default)
			)
			(layer "B.SilkS")
		)
		(fp_line
			(start 1.524 -0.762)
			(end -1.524 -0.762)
			(stroke
				(width 0.1524)
				(type default)
			)
			(layer "B.SilkS")
		)
		(fp_line
			(start -1.524 0.762)
			(end 1.524 0.762)
			(stroke
				(width 0.1524)
				(type default)
			)
			(layer "B.SilkS")
		)
		(fp_line
			(start -1.524 -0.762)
			(end -1.524 0.762)
			(stroke
				(width 0.1524)
				(type default)
			)
			(layer "B.SilkS")
		)
		(fp_line
			(start 1.1049 0.724916)
			(end -1.1049 0.724916)
			(stroke
				(width 0.1)
				(type default)
			)
			(layer "B.Fab")
		)
		(fp_line
			(start 1.1049 -0.724916)
			(end 1.1049 0.724916)
			(stroke
				(width 0.1)
				(type default)
			)
			(layer "B.Fab")
		)
		(fp_line
			(start -1.1049 0.724916)
			(end -1.1049 -0.724916)
			(stroke
				(width 0.1)
				(type default)
			)
			(layer "B.Fab")
		)
		(fp_line
			(start -1.1049 -0.724916)
			(end 1.1049 -0.724916)
			(stroke
				(width 0.1)
				(type default)
			)
			(layer "B.Fab")
		)
		(pad "1" smd rect
			(at 0.889 0 180)
			(size 1.016 1.27)
			(layers "B.Cu" "B.Mask" "B.Paste")
			(net "P1V25_PEX2_R")
		)
		(pad "2" smd rect
			(at -0.889 0 180)
			(size 1.016 1.27)
			(layers "B.Cu" "B.Mask" "B.Paste")
			(net "GND")
		)
	)
	(footprint ""
		(layer "B.Cu")
		(at 193.641726 -100.056696 180)
		(property "Reference" "R179"
			(at 0 0 0)
			(layer "B.SilkS")
			(hide yes)
			(effects
				(font
					(size 1.27 1.27)
				)
				(justify mirror)
			)
		)
		(property "Value" ""
			(at 0 0 0)
			(layer "B.Fab")
			(effects
				(font
					(size 1.27 1.27)
				)
				(justify mirror)
			)
		)
		(duplicate_pad_numbers_are_jumpers no)
		(fp_line
			(start 0.7874 0.4064)
			(end 0.7874 -0.4064)
			(stroke
				(width 0.1524)
				(type default)
			)
			(layer "B.SilkS")
		)
		(fp_line
			(start 0.7874 -0.4064)
			(end -0.7874 -0.4064)
			(stroke
				(width 0.1524)
				(type default)
			)
			(layer "B.SilkS")
		)
		(fp_line
			(start -0.7874 0.4064)
			(end 0.7874 0.4064)
			(stroke
				(width 0.1524)
				(type default)
			)
			(layer "B.SilkS")
		)
		(fp_line
			(start -0.7874 -0.4064)
			(end -0.7874 0.4064)
			(stroke
				(width 0.1524)
				(type default)
			)
			(layer "B.SilkS")
		)
		(fp_line
			(start 0.67945 0.3048)
			(end 0.67945 -0.305054)
			(stroke
				(width 0.1)
				(type default)
			)
			(layer "B.Fab")
		)
		(fp_line
			(start 0.67945 -0.305054)
			(end 0.12065 -0.305054)
			(stroke
				(width 0.1)
				(type default)
			)
			(layer "B.Fab")
		)
		(fp_line
			(start 0.12065 0.3048)
			(end 0.67945 0.3048)
			(stroke
				(width 0.1)
				(type default)
			)
			(layer "B.Fab")
		)
		(fp_line
			(start 0.12065 0.2794)
			(end 0.12065 0.3048)
			(stroke
				(width 0.1)
				(type default)
			)
			(layer "B.Fab")
		)
		(fp_line
			(start 0.12065 -0.2794)
			(end -0.12065 -0.2794)
			(stroke
				(width 0.1)
				(type default)
			)
			(layer "B.Fab")
		)
		(fp_line
			(start 0.12065 -0.305054)
			(end 0.12065 -0.2794)
			(stroke
				(width 0.1)
				(type default)
			)
			(layer "B.Fab")
		)
		(fp_line
			(start -0.120396 0.3048)
			(end -0.120396 0.2794)
			(stroke
				(width 0.1)
				(type default)
			)
			(layer "B.Fab")
		)
		(fp_line
			(start -0.120396 0.2794)
			(end 0.12065 0.2794)
			(stroke
				(width 0.1)
				(type default)
			)
			(layer "B.Fab")
		)
		(fp_line
			(start -0.12065 -0.2794)
			(end -0.12065 -0.3048)
			(stroke
				(width 0.1)
				(type default)
			)
			(layer "B.Fab")
		)
		(fp_line
			(start -0.12065 -0.3048)
			(end -0.67945 -0.3048)
			(stroke
				(width 0.1)
				(type default)
			)
			(layer "B.Fab")
		)
		(fp_line
			(start -0.67945 0.3048)
			(end -0.120396 0.3048)
			(stroke
				(width 0.1)
				(type default)
			)
			(layer "B.Fab")
		)
		(fp_line
			(start -0.67945 -0.3048)
			(end -0.67945 0.3048)
			(stroke
				(width 0.1)
				(type default)
			)
			(layer "B.Fab")
		)
		(pad "1" smd circle
			(at 0.40005 0)
			(size 0 0)
			(layers "B.Cu" "B.Mask" "B.Paste")
			(net "NIC3_SLOT_ID0")
		)
		(pad "2" smd circle
			(at -0.40005 0)
			(size 0 0)
			(layers "B.Cu" "B.Mask" "B.Paste")
			(net "GND")
		)
	)
	(footprint ""
		(layer "B.Cu")
		(at 146.685254 -209.562192 -90)
		(property "Reference" "R972"
			(at 0 0 90)
			(layer "B.SilkS")
			(hide yes)
			(effects
				(font
					(size 1.27 1.27)
				)
				(justify mirror)
			)
		)
		(property "Value" ""
			(at 0 0 90)
			(layer "B.Fab")
			(effects
				(font
					(size 1.27 1.27)
				)
				(justify mirror)
			)
		)
		(duplicate_pad_numbers_are_jumpers no)
		(fp_line
			(start -0.7874 0.4064)
			(end 0.7874 0.4064)
			(stroke
				(width 0.1524)
				(type default)
			)
			(layer "B.SilkS")
		)
		(fp_line
			(start 0.7874 0.4064)
			(end 0.7874 -0.4064)
			(stroke
				(width 0.1524)
				(type default)
			)
			(layer "B.SilkS")
		)
		(fp_line
			(start -0.7874 -0.4064)
			(end -0.7874 0.4064)
			(stroke
				(width 0.1524)
				(type default)
			)
			(layer "B.SilkS")
		)
		(fp_line
			(start 0.7874 -0.4064)
			(end -0.7874 -0.4064)
			(stroke
				(width 0.1524)
				(type default)
			)
			(layer "B.SilkS")
		)
		(fp_line
			(start -0.67945 0.3048)
			(end -0.120396 0.3048)
			(stroke
				(width 0.1)
				(type default)
			)
			(layer "B.Fab")
		)
		(fp_line
			(start -0.120396 0.3048)
			(end -0.120396 0.2794)
			(stroke
				(width 0.1)
				(type default)
			)
			(layer "B.Fab")
		)
		(fp_line
			(start 0.12065 0.3048)
			(end 0.67945 0.3048)
			(stroke
				(width 0.1)
				(type default)
			)
			(layer "B.Fab")
		)
		(fp_line
			(start 0.67945 0.3048)
			(end 0.67945 -0.305054)
			(stroke
				(width 0.1)
				(type default)
			)
			(layer "B.Fab")
		)
		(fp_line
			(start -0.120396 0.2794)
			(end 0.12065 0.2794)
			(stroke
				(width 0.1)
				(type default)
			)
			(layer "B.Fab")
		)
		(fp_line
			(start 0.12065 0.2794)
			(end 0.12065 0.3048)
			(stroke
				(width 0.1)
				(type default)
			)
			(layer "B.Fab")
		)
		(fp_line
			(start -0.12065 -0.2794)
			(end -0.12065 -0.3048)
			(stroke
				(width 0.1)
				(type default)
			)
			(layer "B.Fab")
		)
		(fp_line
			(start 0.12065 -0.2794)
			(end -0.12065 -0.2794)
			(stroke
				(width 0.1)
				(type default)
			)
			(layer "B.Fab")
		)
		(fp_line
			(start -0.67945 -0.3048)
			(end -0.67945 0.3048)
			(stroke
				(width 0.1)
				(type default)
			)
			(layer "B.Fab")
		)
		(fp_line
			(start -0.12065 -0.3048)
			(end -0.67945 -0.3048)
			(stroke
				(width 0.1)
				(type default)
			)
			(layer "B.Fab")
		)
		(fp_line
			(start 0.12065 -0.305054)
			(end 0.12065 -0.2794)
			(stroke
				(width 0.1)
				(type default)
			)
			(layer "B.Fab")
		)
		(fp_line
			(start 0.67945 -0.305054)
			(end 0.12065 -0.305054)
			(stroke
				(width 0.1)
				(type default)
			)
			(layer "B.Fab")
		)
		(pad "1" smd circle
			(at 0.40005 0 90)
			(size 0 0)
			(layers "B.Cu" "B.Mask" "B.Paste")
			(net "UART_PEX1_CLI_BUF_RX")
		)
		(pad "2" smd circle
			(at -0.40005 0 90)
			(size 0 0)
			(layers "B.Cu" "B.Mask" "B.Paste")
			(net "P1V8_PEX")
		)
	)
	(footprint ""
		(layer "B.Cu")
		(at 191.823848 -291.624766 90)
		(property "Reference" "R986"
			(at 0 0 90)
			(layer "B.SilkS")
			(hide yes)
			(effects
				(font
					(size 1.27 1.27)
				)
				(justify mirror)
			)
		)
		(property "Value" ""
			(at 0 0 90)
			(layer "B.Fab")
			(effects
				(font
					(size 1.27 1.27)
				)
				(justify mirror)
			)
		)
		(duplicate_pad_numbers_are_jumpers no)
		(fp_line
			(start 0.7874 -0.4064)
			(end -0.7874 -0.4064)
			(stroke
				(width 0.1524)
				(type default)
			)
			(layer "B.SilkS")
		)
		(fp_line
			(start -0.7874 -0.4064)
			(end -0.7874 0.4064)
			(stroke
				(width 0.1524)
				(type default)
			)
			(layer "B.SilkS")
		)
		(fp_line
			(start 0.7874 0.4064)
			(end 0.7874 -0.4064)
			(stroke
				(width 0.1524)
				(type default)
			)
			(layer "B.SilkS")
		)
		(fp_line
			(start -0.7874 0.4064)
			(end 0.7874 0.4064)
			(stroke
				(width 0.1524)
				(type default)
			)
			(layer "B.SilkS")
		)
		(fp_line
			(start 0.67945 -0.305054)
			(end 0.12065 -0.305054)
			(stroke
				(width 0.1)
				(type default)
			)
			(layer "B.Fab")
		)
		(fp_line
			(start 0.12065 -0.305054)
			(end 0.12065 -0.2794)
			(stroke
				(width 0.1)
				(type default)
			)
			(layer "B.Fab")
		)
		(fp_line
			(start -0.12065 -0.3048)
			(end -0.67945 -0.3048)
			(stroke
				(width 0.1)
				(type default)
			)
			(layer "B.Fab")
		)
		(fp_line
			(start -0.67945 -0.3048)
			(end -0.67945 0.3048)
			(stroke
				(width 0.1)
				(type default)
			)
			(layer "B.Fab")
		)
		(fp_line
			(start 0.12065 -0.2794)
			(end -0.12065 -0.2794)
			(stroke
				(width 0.1)
				(type default)
			)
			(layer "B.Fab")
		)
		(fp_line
			(start -0.12065 -0.2794)
			(end -0.12065 -0.3048)
			(stroke
				(width 0.1)
				(type default)
			)
			(layer "B.Fab")
		)
		(fp_line
			(start 0.12065 0.2794)
			(end 0.12065 0.3048)
			(stroke
				(width 0.1)
				(type default)
			)
			(layer "B.Fab")
		)
		(fp_line
			(start -0.120396 0.2794)
			(end 0.12065 0.2794)
			(stroke
				(width 0.1)
				(type default)
			)
			(layer "B.Fab")
		)
		(fp_line
			(start 0.67945 0.3048)
			(end 0.67945 -0.305054)
			(stroke
				(width 0.1)
				(type default)
			)
			(layer "B.Fab")
		)
		(fp_line
			(start 0.12065 0.3048)
			(end 0.67945 0.3048)
			(stroke
				(width 0.1)
				(type default)
			)
			(layer "B.Fab")
		)
		(fp_line
			(start -0.120396 0.3048)
			(end -0.120396 0.2794)
			(stroke
				(width 0.1)
				(type default)
			)
			(layer "B.Fab")
		)
		(fp_line
			(start -0.67945 0.3048)
			(end -0.120396 0.3048)
			(stroke
				(width 0.1)
				(type default)
			)
			(layer "B.Fab")
		)
		(pad "1" smd circle
			(at 0.40005 0 270)
			(size 0 0)
			(layers "B.Cu" "B.Mask" "B.Paste")
			(net "UART_PEX1_CLI_TX")
		)
		(pad "2" smd circle
			(at -0.40005 0 270)
			(size 0 0)
			(layers "B.Cu" "B.Mask" "B.Paste")
			(net "UART_PEX1_CLI_R_TX")
		)
	)
	(footprint ""
		(layer "B.Cu")
		(at 133.932422 -222.658432)
		(property "Reference" "C2307"
			(at 0 0 0)
			(layer "B.SilkS")
			(hide yes)
			(effects
				(font
					(size 1.27 1.27)
				)
				(justify mirror)
			)
		)
		(property "Value" ""
			(at 0 0 0)
			(layer "B.Fab")
			(effects
				(font
					(size 1.27 1.27)
				)
				(justify mirror)
			)
		)
		(duplicate_pad_numbers_are_jumpers no)
		(fp_line
			(start -0.7874 -0.4064)
			(end -0.7874 0.4064)
			(stroke
				(width 0.1524)
				(type default)
			)
			(layer "B.SilkS")
		)
		(fp_line
			(start -0.7874 0.4064)
			(end 0.7874 0.4064)
			(stroke
				(width 0.1524)
				(type default)
			)
			(layer "B.SilkS")
		)
		(fp_line
			(start 0.7874 -0.4064)
			(end -0.7874 -0.4064)
			(stroke
				(width 0.1524)
				(type default)
			)
			(layer "B.SilkS")
		)
		(fp_line
			(start 0.7874 0.4064)
			(end 0.7874 -0.4064)
			(stroke
				(width 0.1524)
				(type default)
			)
			(layer "B.SilkS")
		)
		(fp_line
			(start -0.67945 -0.3048)
			(end -0.67945 0.3048)
			(stroke
				(width 0.1)
				(type default)
			)
			(layer "B.Fab")
		)
		(fp_line
			(start -0.67945 0.3048)
			(end -0.120396 0.3048)
			(stroke
				(width 0.1)
				(type default)
			)
			(layer "B.Fab")
		)
		(fp_line
			(start -0.12065 -0.3048)
			(end -0.67945 -0.3048)
			(stroke
				(width 0.1)
				(type default)
			)
			(layer "B.Fab")
		)
		(fp_line
			(start -0.12065 -0.2794)
			(end -0.12065 -0.3048)
			(stroke
				(width 0.1)
				(type default)
			)
			(layer "B.Fab")
		)
		(fp_line
			(start -0.120396 0.2794)
			(end 0.12065 0.2794)
			(stroke
				(width 0.1)
				(type default)
			)
			(layer "B.Fab")
		)
		(fp_line
			(start -0.120396 0.3048)
			(end -0.120396 0.2794)
			(stroke
				(width 0.1)
				(type default)
			)
			(layer "B.Fab")
		)
		(fp_line
			(start 0.12065 -0.305054)
			(end 0.12065 -0.2794)
			(stroke
				(width 0.1)
				(type default)
			)
			(layer "B.Fab")
		)
		(fp_line
			(start 0.12065 -0.2794)
			(end -0.12065 -0.2794)
			(stroke
				(width 0.1)
				(type default)
			)
			(layer "B.Fab")
		)
		(fp_line
			(start 0.12065 0.2794)
			(end 0.12065 0.3048)
			(stroke
				(width 0.1)
				(type default)
			)
			(layer "B.Fab")
		)
		(fp_line
			(start 0.12065 0.3048)
			(end 0.67945 0.3048)
			(stroke
				(width 0.1)
				(type default)
			)
			(layer "B.Fab")
		)
		(fp_line
			(start 0.67945 -0.305054)
			(end 0.12065 -0.305054)
			(stroke
				(width 0.1)
				(type default)
			)
			(layer "B.Fab")
		)
		(fp_line
			(start 0.67945 0.3048)
			(end 0.67945 -0.305054)
			(stroke
				(width 0.1)
				(type default)
			)
			(layer "B.Fab")
		)
		(pad "1" smd circle
			(at 0.40005 0 180)
			(size 0 0)
			(layers "B.Cu" "B.Mask" "B.Paste")
			(net "GND")
		)
		(pad "2" smd circle
			(at -0.40005 0 180)
			(size 0 0)
			(layers "B.Cu" "B.Mask" "B.Paste")
			(net "P3V3_AUX")
		)
	)
	(footprint ""
		(layer "B.Cu")
		(at 52.049934 -301.599854 -90)
		(property "Reference" "C1180"
			(at 0 0 90)
			(layer "B.SilkS")
			(hide yes)
			(effects
				(font
					(size 1.27 1.27)
				)
				(justify mirror)
			)
		)
		(property "Value" ""
			(at 0 0 90)
			(layer "B.Fab")
			(effects
				(font
					(size 1.27 1.27)
				)
				(justify mirror)
			)
		)
		(duplicate_pad_numbers_are_jumpers no)
		(fp_line
			(start -0.299974 0.150114)
			(end 0.299974 0.150114)
			(stroke
				(width 0.1)
				(type default)
			)
			(layer "B.Fab")
		)
		(fp_line
			(start 0.299974 0.150114)
			(end 0.299974 -0.150114)
			(stroke
				(width 0.1)
				(type default)
			)
			(layer "B.Fab")
		)
		(fp_line
			(start -0.299974 -0.150114)
			(end -0.299974 0.150114)
			(stroke
				(width 0.1)
				(type default)
			)
			(layer "B.Fab")
		)
		(fp_line
			(start 0.299974 -0.150114)
			(end -0.299974 -0.150114)
			(stroke
				(width 0.1)
				(type default)
			)
			(layer "B.Fab")
		)
		(pad "1" smd rect
			(at 0.2667 0 90)
			(size 0.3048 0.381)
			(layers "B.Cu" "B.Mask" "B.Paste")
			(net "P0V8_SERDES_VDDA_PEX0")
		)
		(pad "2" smd rect
			(at -0.2667 0 90)
			(size 0.3048 0.381)
			(layers "B.Cu" "B.Mask" "B.Paste")
			(net "GND")
		)
	)
)
